# SCM (Grand Teton) — schematic netlist excerpt (pin names and nets, part order shuffled) for the footprints in the layout excerpt that follows; sources: Cadence DE-HDL packaged netlist, KiCad conversion of 12092022_DA0F0TMDCD0_F0T_Management_Board_D_brd_V3_OCP.brd

R792  Q_RES  2K 1% CHIP  pkg 0402LF  page 15 : A = P2V5_SENSOR ; B = GND
R370  Q_RES  120 1% CHIP  pkg 0402LF  page 20 : A = M_BMC_DDR4_MBG0 ; B = P1V2_AUX

(kicad_pcb
	(version 20260206)
	(generator "pcbnew")
	(generator_version "10.0")
	(general
		(thickness 1.6)
		(legacy_teardrops no)
	)
	(paper "A4")
	(title_block
		(title "12092022_DA0F0TMDCD0_F0T_Management_Board_D_brd_V3_OCP.brd")
		(comment 1 "Grand Teton / footprints 1324-1325 of 1440")
	)
	(layers
		(0 "F.Cu" signal "TOP")
		(4 "In1.Cu" signal "GND")
		(6 "In2.Cu" signal "IN1")
		(8 "In3.Cu" signal "GND1")
		(10 "In4.Cu" signal "IN2")
		(12 "In5.Cu" signal "VCC")
		(14 "In6.Cu" signal "VCC1")
		(16 "In7.Cu" signal "IN3")
		(18 "In8.Cu" signal "GND2")
		(20 "In9.Cu" signal "IN4")
		(22 "In10.Cu" signal "GND3")
		(2 "B.Cu" signal "BOTTOM")
		(9 "F.Adhes" user "F.Adhesive")
		(11 "B.Adhes" user "B.Adhesive")
		(13 "F.Paste" user "Package Geometry/Pastemask Top")
		(15 "B.Paste" user "Package Geometry/Pastemask Bottom")
		(5 "F.SilkS" user "Ref Des/Silkscreen Top")
		(7 "B.SilkS" user "Ref Des/Silkscreen Bottom")
		(1 "F.Mask" user "Board Geometry/Soldermask Top")
		(3 "B.Mask" user "Board Geometry/Soldermask Bottom")
		(17 "Dwgs.User" user "User.Drawings")
		(19 "Cmts.User" user "User.Comments")
		(21 "Eco1.User" user "User.Eco1")
		(23 "Eco2.User" user "User.Eco2")
		(25 "Edge.Cuts" user "Board Geometry/Outline")
		(27 "Margin" user)
		(31 "F.CrtYd" user "Package Geometry/Place Bound Top")
		(29 "B.CrtYd" user "Package Geometry/Place Bound Bottom")
		(35 "F.Fab" user "Ref Des/Assembly Top")
		(33 "B.Fab" user "Ref Des/Assembly Bottom")
	)
	(footprint ""
		(layer "B.Cu")
		(at 81.161636 -38.957758 180)
		(property "Reference" "R370"
			(at 0 0 0)
			(layer "B.SilkS")
			(hide yes)
			(effects
				(font
					(size 1.27 1.27)
				)
				(justify mirror)
			)
		)
		(property "Value" ""
			(at 0 0 0)
			(layer "B.Fab")
			(effects
				(font
					(size 1.27 1.27)
				)
				(justify mirror)
			)
		)
		(duplicate_pad_numbers_are_jumpers no)
		(fp_line
			(start 0.7874 0.4064)
			(end 0.7874 -0.4064)
			(stroke
				(width 0.1524)
				(type default)
			)
			(layer "B.SilkS")
		)
		(fp_line
			(start 0.7874 -0.4064)
			(end -0.7874 -0.4064)
			(stroke
				(width 0.1524)
				(type default)
			)
			(layer "B.SilkS")
		)
		(fp_line
			(start -0.7874 0.4064)
			(end 0.7874 0.4064)
			(stroke
				(width 0.1524)
				(type default)
			)
			(layer "B.SilkS")
		)
		(fp_line
			(start -0.7874 -0.4064)
			(end -0.7874 0.4064)
			(stroke
				(width 0.1524)
				(type default)
			)
			(layer "B.SilkS")
		)
		(fp_line
			(start 0.67945 0.3048)
			(end 0.67945 -0.305054)
			(stroke
				(width 0.1)
				(type default)
			)
			(layer "B.Fab")
		)
		(fp_line
			(start 0.67945 -0.305054)
			(end 0.12065 -0.305054)
			(stroke
				(width 0.1)
				(type default)
			)
			(layer "B.Fab")
		)
		(fp_line
			(start 0.12065 0.3048)
			(end 0.67945 0.3048)
			(stroke
				(width 0.1)
				(type default)
			)
			(layer "B.Fab")
		)
		(fp_line
			(start 0.12065 0.2794)
			(end 0.12065 0.3048)
			(stroke
				(width 0.1)
				(type default)
			)
			(layer "B.Fab")
		)
		(fp_line
			(start 0.12065 -0.2794)
			(end -0.12065 -0.2794)
			(stroke
				(width 0.1)
				(type default)
			)
			(layer "B.Fab")
		)
		(fp_line
			(start 0.12065 -0.305054)
			(end 0.12065 -0.2794)
			(stroke
				(width 0.1)
				(type default)
			)
			(layer "B.Fab")
		)
		(fp_line
			(start -0.120396 0.3048)
			(end -0.120396 0.2794)
			(stroke
				(width 0.1)
				(type default)
			)
			(layer "B.Fab")
		)
		(fp_line
			(start -0.120396 0.2794)
			(end 0.12065 0.2794)
			(stroke
				(width 0.1)
				(type default)
			)
			(layer "B.Fab")
		)
		(fp_line
			(start -0.12065 -0.2794)
			(end -0.12065 -0.3048)
			(stroke
				(width 0.1)
				(type default)
			)
			(layer "B.Fab")
		)
		(fp_line
			(start -0.12065 -0.3048)
			(end -0.67945 -0.3048)
			(stroke
				(width 0.1)
				(type default)
			)
			(layer "B.Fab")
		)
		(fp_line
			(start -0.67945 0.3048)
			(end -0.120396 0.3048)
			(stroke
				(width 0.1)
				(type default)
			)
			(layer "B.Fab")
		)
		(fp_line
			(start -0.67945 -0.3048)
			(end -0.67945 0.3048)
			(stroke
				(width 0.1)
				(type default)
			)
			(layer "B.Fab")
		)
		(pad "1" smd circle
			(at 0.40005 0)
			(size 0 0)
			(layers "B.Cu" "B.Mask" "B.Paste")
			(net "M_BMC_DDR4_MBG0")
		)
		(pad "2" smd circle
			(at -0.40005 0)
			(size 0 0)
			(layers "B.Cu" "B.Mask" "B.Paste")
			(net "P1V2_AUX")
		)
	)
	(footprint ""
		(layer "B.Cu")
		(at 54.313582 -68.349368 90)
		(property "Reference" "R792"
			(at 0 0 90)
			(layer "B.SilkS")
			(hide yes)
			(effects
				(font
					(size 1.27 1.27)
				)
				(justify mirror)
			)
		)
		(property "Value" ""
			(at 0 0 90)
			(layer "B.Fab")
			(effects
				(font
					(size 1.27 1.27)
				)
				(justify mirror)
			)
		)
		(duplicate_pad_numbers_are_jumpers no)
		(fp_line
			(start 0.7874 -0.4064)
			(end -0.7874 -0.4064)
			(stroke
				(width 0.1524)
				(type default)
			)
			(layer "B.SilkS")
		)
		(fp_line
			(start -0.7874 -0.4064)
			(end -0.7874 0.4064)
			(stroke
				(width 0.1524)
				(type default)
			)
			(layer "B.SilkS")
		)
		(fp_line
			(start 0.7874 0.4064)
			(end 0.7874 -0.4064)
			(stroke
				(width 0.1524)
				(type default)
			)
			(layer "B.SilkS")
		)
		(fp_line
			(start -0.7874 0.4064)
			(end 0.7874 0.4064)
			(stroke
				(width 0.1524)
				(type default)
			)
			(layer "B.SilkS")
		)
		(fp_line
			(start 0.67945 -0.305054)
			(end 0.12065 -0.305054)
			(stroke
				(width 0.1)
				(type default)
			)
			(layer "B.Fab")
		)
		(fp_line
			(start 0.12065 -0.305054)
			(end 0.12065 -0.2794)
			(stroke
				(width 0.1)
				(type default)
			)
			(layer "B.Fab")
		)
		(fp_line
			(start -0.12065 -0.3048)
			(end -0.67945 -0.3048)
			(stroke
				(width 0.1)
				(type default)
			)
			(layer "B.Fab")
		)
		(fp_line
			(start -0.67945 -0.3048)
			(end -0.67945 0.3048)
			(stroke
				(width 0.1)
				(type default)
			)
			(layer "B.Fab")
		)
		(fp_line
			(start 0.12065 -0.2794)
			(end -0.12065 -0.2794)
			(stroke
				(width 0.1)
				(type default)
			)
			(layer "B.Fab")
		)
		(fp_line
			(start -0.12065 -0.2794)
			(end -0.12065 -0.3048)
			(stroke
				(width 0.1)
				(type default)
			)
			(layer "B.Fab")
		)
		(fp_line
			(start 0.12065 0.2794)
			(end 0.12065 0.3048)
			(stroke
				(width 0.1)
				(type default)
			)
			(layer "B.Fab")
		)
		(fp_line
			(start -0.120396 0.2794)
			(end 0.12065 0.2794)
			(stroke
				(width 0.1)
				(type default)
			)
			(layer "B.Fab")
		)
		(fp_line
			(start 0.67945 0.3048)
			(end 0.67945 -0.305054)
			(stroke
				(width 0.1)
				(type default)
			)
			(layer "B.Fab")
		)
		(fp_line
			(start 0.12065 0.3048)
			(end 0.67945 0.3048)
			(stroke
				(width 0.1)
				(type default)
			)
			(layer "B.Fab")
		)
		(fp_line
			(start -0.120396 0.3048)
			(end -0.120396 0.2794)
			(stroke
				(width 0.1)
				(type default)
			)
			(layer "B.Fab")
		)
		(fp_line
			(start -0.67945 0.3048)
			(end -0.120396 0.3048)
			(stroke
				(width 0.1)
				(type default)
			)
			(layer "B.Fab")
		)
		(pad "1" smd circle
			(at 0.40005 0 270)
			(size 0 0)
			(layers "B.Cu" "B.Mask" "B.Paste")
			(net "P2V5_SENSOR")
		)
		(pad "2" smd circle
			(at -0.40005 0 270)
			(size 0 0)
			(layers "B.Cu" "B.Mask" "B.Paste")
			(net "GND")
		)
	)
)
